(kicad_sch
	(version 20250114)
	(generator "eeschema")
	(generator_version "9.0")
	(paper "A3")
	(title_block
		(title "PolarFire SoM")
		(date "2025-07-22")
		(rev "1.1.4")
		(company "Antmicro Ltd")
		(comment 1 "www.antmicro.com")
	)
	(text "Tie to 3V3 to disable TMDS output"
		(exclude_from_sim no)
		(at 214.63 119.38 0)
		(effects
			(font
				(size 1.27 1.27)
			)
			(justify right bottom)
		)
	)
	(text "HDMI Driver"
		(exclude_from_sim no)
		(at 16.51 22.86 0)
		(effects
			(font
				(size 4 4)
				(thickness 0.8)
				(bold yes)
			)
			(justify left bottom)
		)
	)
	(junction
		(at 321.31 138.43)
		(diameter 0)
		(color 0 0 0 0)
	)
	(junction
		(at 128.27 113.03)
		(diameter 0)
		(color 0 0 0 0)
	)
	(junction
		(at 241.3 124.46)
		(diameter 0)
		(color 0 0 0 0)
	)
	(junction
		(at 123.19 99.06)
		(diameter 0)
		(color 0 0 0 0)
	)
	(junction
		(at 245.11 163.83)
		(diameter 0)
		(color 0 0 0 0)
	)
	(junction
		(at 128.27 99.06)
		(diameter 0)
		(color 0 0 0 0)
	)
	(junction
		(at 133.35 113.03)
		(diameter 0)
		(color 0 0 0 0)
	)
	(junction
		(at 317.5 154.94)
		(diameter 0)
		(color 0 0 0 0)
	)
	(junction
		(at 321.31 157.48)
		(diameter 0)
		(color 0 0 0 0)
	)
	(junction
		(at 118.11 99.06)
		(diameter 0)
		(color 0 0 0 0)
	)
	(junction
		(at 133.35 99.06)
		(diameter 0)
		(color 0 0 0 0)
	)
	(junction
		(at 123.19 113.03)
		(diameter 0)
		(color 0 0 0 0)
	)
	(bus_entry
		(at 99.06 157.48)
		(size -2.54 -2.54)
		(stroke
			(width 0)
			(type default)
		)
	)
	(bus_entry
		(at 198.12 157.48)
		(size -2.54 -2.54)
		(stroke
			(width 0)
			(type default)
		)
	)
	(bus_entry
		(at 198.12 154.94)
		(size -2.54 -2.54)
		(stroke
			(width 0)
			(type default)
		)
	)
	(bus_entry
		(at 306.07 140.97)
		(size 2.54 -2.54)
		(stroke
			(width 0)
			(type default)
		)
	)
	(bus_entry
		(at 306.07 148.59)
		(size 2.54 -2.54)
		(stroke
			(width 0)
			(type default)
		)
	)
	(bus_entry
		(at 337.82 154.94)
		(size 2.54 -2.54)
		(stroke
			(width 0)
			(type default)
		)
	)
	(bus_entry
		(at 306.07 130.81)
		(size 2.54 -2.54)
		(stroke
			(width 0)
			(type default)
		)
	)
	(bus_entry
		(at 306.07 133.35)
		(size 2.54 -2.54)
		(stroke
			(width 0)
			(type default)
		)
	)
	(bus_entry
		(at 306.07 143.51)
		(size 2.54 -2.54)
		(stroke
			(width 0)
			(type default)
		)
	)
	(bus_entry
		(at 99.06 160.02)
		(size -2.54 -2.54)
		(stroke
			(width 0)
			(type default)
		)
	)
	(bus_entry
		(at 337.82 157.48)
		(size 2.54 -2.54)
		(stroke
			(width 0)
			(type default)
		)
	)
	(bus_entry
		(at 306.07 146.05)
		(size 2.54 -2.54)
		(stroke
			(width 0)
			(type default)
		)
	)
	(bus_entry
		(at 99.06 152.4)
		(size -2.54 -2.54)
		(stroke
			(width 0)
			(type default)
		)
	)
	(bus_entry
		(at 99.06 162.56)
		(size -2.54 -2.54)
		(stroke
			(width 0)
			(type default)
		)
	)
	(bus_entry
		(at 306.07 135.89)
		(size 2.54 -2.54)
		(stroke
			(width 0)
			(type default)
		)
	)
	(bus_entry
		(at 99.06 149.86)
		(size -2.54 -2.54)
		(stroke
			(width 0)
			(type default)
		)
	)
	(bus_entry
		(at 99.06 154.94)
		(size -2.54 -2.54)
		(stroke
			(width 0)
			(type default)
		)
	)
	(bus_entry
		(at 99.06 167.64)
		(size -2.54 -2.54)
		(stroke
			(width 0)
			(type default)
		)
	)
	(bus_entry
		(at 306.07 138.43)
		(size 2.54 -2.54)
		(stroke
			(width 0)
			(type default)
		)
	)
	(bus_entry
		(at 99.06 165.1)
		(size -2.54 -2.54)
		(stroke
			(width 0)
			(type default)
		)
	)
	(bus
		(pts
			(xy 308.61 130.81) (xy 308.61 133.35)
		)
		(stroke
			(width 0)
			(type default)
		)
	)
	(wire
		(pts
			(xy 123.19 113.03) (xy 123.19 107.95)
		)
		(stroke
			(width 0)
			(type default)
		)
	)
	(wire
		(pts
			(xy 278.13 135.89) (xy 306.07 135.89)
		)
		(stroke
			(width 0)
			(type default)
		)
	)
	(wire
		(pts
			(xy 317.5 154.94) (xy 337.82 154.94)
		)
		(stroke
			(width 0)
			(type default)
		)
	)
	(wire
		(pts
			(xy 321.31 138.43) (xy 321.31 140.97)
		)
		(stroke
			(width 0)
			(type default)
		)
	)
	(bus
		(pts
			(xy 308.61 135.89) (xy 308.61 138.43)
		)
		(stroke
			(width 0)
			(type default)
		)
	)
	(wire
		(pts
			(xy 278.13 146.05) (xy 306.07 146.05)
		)
		(stroke
			(width 0)
			(type default)
		)
	)
	(bus
		(pts
			(xy 308.61 138.43) (xy 308.61 140.97)
		)
		(stroke
			(width 0)
			(type default)
		)
	)
	(wire
		(pts
			(xy 317.5 138.43) (xy 321.31 138.43)
		)
		(stroke
			(width 0)
			(type default)
		)
	)
	(wire
		(pts
			(xy 208.28 146.05) (xy 250.19 146.05)
		)
		(stroke
			(width 0)
			(type default)
		)
	)
	(bus
		(pts
			(xy 340.36 152.4) (xy 340.36 154.94)
		)
		(stroke
			(width 0)
			(type default)
		)
	)
	(wire
		(pts
			(xy 151.13 149.86) (xy 134.62 149.86)
		)
		(stroke
			(width 0)
			(type default)
		)
	)
	(polyline
		(pts
			(xy 224.79 119.38) (xy 224.79 127)
		)
		(stroke
			(width 0)
			(type default)
		)
	)
	(wire
		(pts
			(xy 99.06 162.56) (xy 124.46 162.56)
		)
		(stroke
			(width 0)
			(type default)
		)
	)
	(wire
		(pts
			(xy 133.35 99.06) (xy 128.27 99.06)
		)
		(stroke
			(width 0)
			(type default)
		)
	)
	(wire
		(pts
			(xy 245.11 163.83) (xy 245.11 168.91)
		)
		(stroke
			(width 0)
			(type default)
		)
	)
	(wire
		(pts
			(xy 151.13 162.56) (xy 134.62 162.56)
		)
		(stroke
			(width 0)
			(type default)
		)
	)
	(bus
		(pts
			(xy 311.15 125.73) (xy 309.88 125.73)
		)
		(stroke
			(width 0)
			(type default)
		)
	)
	(polyline
		(pts
			(xy 224.79 127) (xy 233.68 127)
		)
		(stroke
			(width 0)
			(type default)
		)
	)
	(wire
		(pts
			(xy 100.33 99.06) (xy 106.68 99.06)
		)
		(stroke
			(width 0)
			(type default)
		)
	)
	(wire
		(pts
			(xy 100.33 97.79) (xy 100.33 99.06)
		)
		(stroke
			(width 0)
			(type default)
		)
	)
	(wire
		(pts
			(xy 208.28 143.51) (xy 250.19 143.51)
		)
		(stroke
			(width 0)
			(type default)
		)
	)
	(wire
		(pts
			(xy 278.13 148.59) (xy 306.07 148.59)
		)
		(stroke
			(width 0)
			(type default)
		)
	)
	(wire
		(pts
			(xy 283.21 121.92) (xy 278.13 121.92)
		)
		(stroke
			(width 0)
			(type default)
		)
	)
	(wire
		(pts
			(xy 208.28 148.59) (xy 250.19 148.59)
		)
		(stroke
			(width 0)
			(type default)
		)
	)
	(wire
		(pts
			(xy 118.11 99.06) (xy 123.19 99.06)
		)
		(stroke
			(width 0)
			(type default)
		)
	)
	(wire
		(pts
			(xy 278.13 138.43) (xy 306.07 138.43)
		)
		(stroke
			(width 0)
			(type default)
		)
	)
	(bus
		(pts
			(xy 96.52 147.32) (xy 96.52 149.86)
		)
		(stroke
			(width 0)
			(type default)
		)
	)
	(bus
		(pts
			(xy 308.61 128.27) (xy 308.61 130.81)
		)
		(stroke
			(width 0)
			(type default)
		)
	)
	(wire
		(pts
			(xy 151.13 165.1) (xy 134.62 165.1)
		)
		(stroke
			(width 0)
			(type default)
		)
	)
	(bus
		(pts
			(xy 340.36 151.13) (xy 341.63 149.86)
		)
		(stroke
			(width 0)
			(type default)
		)
	)
	(wire
		(pts
			(xy 99.06 165.1) (xy 124.46 165.1)
		)
		(stroke
			(width 0)
			(type default)
		)
	)
	(bus
		(pts
			(xy 96.52 154.94) (xy 96.52 157.48)
		)
		(stroke
			(width 0)
			(type default)
		)
	)
	(wire
		(pts
			(xy 128.27 107.95) (xy 128.27 113.03)
		)
		(stroke
			(width 0)
			(type default)
		)
	)
	(bus
		(pts
			(xy 96.52 157.48) (xy 96.52 160.02)
		)
		(stroke
			(width 0)
			(type default)
		)
	)
	(wire
		(pts
			(xy 208.28 133.35) (xy 250.19 133.35)
		)
		(stroke
			(width 0)
			(type default)
		)
	)
	(wire
		(pts
			(xy 229.87 124.46) (xy 232.41 124.46)
		)
		(stroke
			(width 0)
			(type default)
		)
	)
	(wire
		(pts
			(xy 151.13 152.4) (xy 134.62 152.4)
		)
		(stroke
			(width 0)
			(type default)
		)
	)
	(wire
		(pts
			(xy 317.5 146.05) (xy 317.5 154.94)
		)
		(stroke
			(width 0)
			(type default)
		)
	)
	(wire
		(pts
			(xy 133.35 113.03) (xy 128.27 113.03)
		)
		(stroke
			(width 0)
			(type default)
		)
	)
	(wire
		(pts
			(xy 133.35 116.84) (xy 133.35 113.03)
		)
		(stroke
			(width 0)
			(type default)
		)
	)
	(wire
		(pts
			(xy 123.19 99.06) (xy 128.27 99.06)
		)
		(stroke
			(width 0)
			(type default)
		)
	)
	(wire
		(pts
			(xy 99.06 149.86) (xy 124.46 149.86)
		)
		(stroke
			(width 0)
			(type default)
		)
	)
	(wire
		(pts
			(xy 283.21 124.46) (xy 278.13 124.46)
		)
		(stroke
			(width 0)
			(type default)
		)
	)
	(wire
		(pts
			(xy 151.13 154.94) (xy 134.62 154.94)
		)
		(stroke
			(width 0)
			(type default)
		)
	)
	(wire
		(pts
			(xy 133.35 107.95) (xy 133.35 113.03)
		)
		(stroke
			(width 0)
			(type default)
		)
	)
	(bus
		(pts
			(xy 195.58 152.4) (xy 195.58 154.94)
		)
		(stroke
			(width 0)
			(type default)
		)
	)
	(bus
		(pts
			(xy 308.61 127) (xy 309.88 125.73)
		)
		(stroke
			(width 0)
			(type default)
		)
	)
	(bus
		(pts
			(xy 340.36 151.13) (xy 340.36 152.4)
		)
		(stroke
			(width 0)
			(type default)
		)
	)
	(wire
		(pts
			(xy 133.35 99.06) (xy 134.62 99.06)
		)
		(stroke
			(width 0)
			(type default)
		)
	)
	(wire
		(pts
			(xy 151.13 160.02) (xy 134.62 160.02)
		)
		(stroke
			(width 0)
			(type default)
		)
	)
	(wire
		(pts
			(xy 123.19 102.87) (xy 123.19 99.06)
		)
		(stroke
			(width 0)
			(type default)
		)
	)
	(bus
		(pts
			(xy 96.52 146.05) (xy 96.52 147.32)
		)
		(stroke
			(width 0)
			(type default)
		)
	)
	(bus
		(pts
			(xy 96.52 152.4) (xy 96.52 154.94)
		)
		(stroke
			(width 0)
			(type default)
		)
	)
	(wire
		(pts
			(xy 111.76 99.06) (xy 118.11 99.06)
		)
		(stroke
			(width 0)
			(type default)
		)
	)
	(wire
		(pts
			(xy 278.13 130.81) (xy 306.07 130.81)
		)
		(stroke
			(width 0)
			(type default)
		)
	)
	(wire
		(pts
			(xy 128.27 113.03) (xy 123.19 113.03)
		)
		(stroke
			(width 0)
			(type default)
		)
	)
	(wire
		(pts
			(xy 228.6 152.4) (xy 250.19 152.4)
		)
		(stroke
			(width 0)
			(type default)
		)
	)
	(wire
		(pts
			(xy 250.19 127) (xy 245.11 127)
		)
		(stroke
			(width 0)
			(type default)
		)
	)
	(wire
		(pts
			(xy 245.11 161.29) (xy 245.11 163.83)
		)
		(stroke
			(width 0)
			(type default)
		)
	)
	(bus
		(pts
			(xy 195.58 151.13) (xy 195.58 152.4)
		)
		(stroke
			(width 0)
			(type default)
		)
	)
	(wire
		(pts
			(xy 245.11 163.83) (xy 250.19 163.83)
		)
		(stroke
			(width 0)
			(type default)
		)
	)
	(wire
		(pts
			(xy 118.11 113.03) (xy 118.11 107.95)
		)
		(stroke
			(width 0)
			(type default)
		)
	)
	(wire
		(pts
			(xy 198.12 154.94) (xy 250.19 154.94)
		)
		(stroke
			(width 0)
			(type default)
		)
	)
	(wire
		(pts
			(xy 198.12 157.48) (xy 250.19 157.48)
		)
		(stroke
			(width 0)
			(type default)
		)
	)
	(wire
		(pts
			(xy 208.28 138.43) (xy 250.19 138.43)
		)
		(stroke
			(width 0)
			(type default)
		)
	)
	(wire
		(pts
			(xy 151.13 167.64) (xy 134.62 167.64)
		)
		(stroke
			(width 0)
			(type default)
		)
	)
	(bus
		(pts
			(xy 194.31 149.86) (xy 195.58 151.13)
		)
		(stroke
			(width 0)
			(type default)
		)
	)
	(wire
		(pts
			(xy 321.31 146.05) (xy 321.31 157.48)
		)
		(stroke
			(width 0)
			(type default)
		)
	)
	(bus
		(pts
			(xy 308.61 133.35) (xy 308.61 135.89)
		)
		(stroke
			(width 0)
			(type default)
		)
	)
	(wire
		(pts
			(xy 208.28 135.89) (xy 250.19 135.89)
		)
		(stroke
			(width 0)
			(type default)
		)
	)
	(wire
		(pts
			(xy 208.28 130.81) (xy 250.19 130.81)
		)
		(stroke
			(width 0)
			(type default)
		)
	)
	(wire
		(pts
			(xy 99.06 152.4) (xy 124.46 152.4)
		)
		(stroke
			(width 0)
			(type default)
		)
	)
	(wire
		(pts
			(xy 254 115.57) (xy 245.11 115.57)
		)
		(stroke
			(width 0)
			(type default)
		)
	)
	(wire
		(pts
			(xy 245.11 121.92) (xy 250.19 121.92)
		)
		(stroke
			(width 0)
			(type default)
		)
	)
	(wire
		(pts
			(xy 278.13 133.35) (xy 306.07 133.35)
		)
		(stroke
			(width 0)
			(type default)
		)
	)
	(bus
		(pts
			(xy 96.52 149.86) (xy 96.52 152.4)
		)
		(stroke
			(width 0)
			(type default)
		)
	)
	(wire
		(pts
			(xy 99.06 157.48) (xy 124.46 157.48)
		)
		(stroke
			(width 0)
			(type default)
		)
	)
	(bus
		(pts
			(xy 308.61 143.51) (xy 308.61 146.05)
		)
		(stroke
			(width 0)
			(type default)
		)
	)
	(wire
		(pts
			(xy 237.49 124.46) (xy 241.3 124.46)
		)
		(stroke
			(width 0)
			(type default)
		)
	)
	(wire
		(pts
			(xy 250.19 161.29) (xy 245.11 161.29)
		)
		(stroke
			(width 0)
			(type default)
		)
	)
	(wire
		(pts
			(xy 99.06 154.94) (xy 124.46 154.94)
		)
		(stroke
			(width 0)
			(type default)
		)
	)
	(wire
		(pts
			(xy 321.31 138.43) (xy 321.31 135.89)
		)
		(stroke
			(width 0)
			(type default)
		)
	)
	(bus
		(pts
			(xy 341.63 149.86) (xy 342.9 149.86)
		)
		(stroke
			(width 0)
			(type default)
		)
	)
	(wire
		(pts
			(xy 245.11 115.57) (xy 245.11 121.92)
		)
		(stroke
			(width 0)
			(type default)
		)
	)
	(bus
		(pts
			(xy 308.61 140.97) (xy 308.61 143.51)
		)
		(stroke
			(width 0)
			(type default)
		)
	)
	(bus
		(pts
			(xy 95.25 144.78) (xy 96.52 146.05)
		)
		(stroke
			(width 0)
			(type default)
		)
	)
	(bus
		(pts
			(xy 308.61 127) (xy 308.61 128.27)
		)
		(stroke
			(width 0)
			(type default)
		)
	)
	(wire
		(pts
			(xy 278.13 157.48) (xy 321.31 157.48)
		)
		(stroke
			(width 0)
			(type default)
		)
	)
	(wire
		(pts
			(xy 278.13 154.94) (xy 317.5 154.94)
		)
		(stroke
			(width 0)
			(type default)
		)
	)
	(wire
		(pts
			(xy 317.5 140.97) (xy 317.5 138.43)
		)
		(stroke
			(width 0)
			(type default)
		)
	)
	(bus
		(pts
			(xy 193.04 149.86) (xy 194.31 149.86)
		)
		(stroke
			(width 0)
			(type default)
		)
	)
	(wire
		(pts
			(xy 99.06 160.02) (xy 124.46 160.02)
		)
		(stroke
			(width 0)
			(type default)
		)
	)
	(bus
		(pts
			(xy 96.52 160.02) (xy 96.52 162.56)
		)
		(stroke
			(width 0)
			(type default)
		)
	)
	(polyline
		(pts
			(xy 224.79 119.38) (xy 180.34 119.38)
		)
		(stroke
			(width 0)
			(type default)
		)
	)
	(bus
		(pts
			(xy 92.71 144.78) (xy 95.25 144.78)
		)
		(stroke
			(width 0)
			(type default)
		)
	)
	(wire
		(pts
			(xy 241.3 124.46) (xy 250.19 124.46)
		)
		(stroke
			(width 0)
			(type default)
		)
	)
	(wire
		(pts
			(xy 133.35 102.87) (xy 133.35 99.06)
		)
		(stroke
			(width 0)
			(type default)
		)
	)
	(wire
		(pts
			(xy 321.31 157.48) (xy 337.82 157.48)
		)
		(stroke
			(width 0)
			(type default)
		)
	)
	(wire
		(pts
			(xy 118.11 102.87) (xy 118.11 99.06)
		)
		(stroke
			(width 0)
			(type default)
		)
	)
	(wire
		(pts
			(xy 278.13 143.51) (xy 306.07 143.51)
		)
		(stroke
			(width 0)
			(type default)
		)
	)
	(wire
		(pts
			(xy 128.27 102.87) (xy 128.27 99.06)
		)
		(stroke
			(width 0)
			(type default)
		)
	)
	(wire
		(pts
			(xy 278.13 152.4) (xy 288.29 152.4)
		)
		(stroke
			(width 0)
			(type default)
		)
	)
	(wire
		(pts
			(xy 99.06 167.64) (xy 124.46 167.64)
		)
		(stroke
			(width 0)
			(type default)
		)
	)
	(wire
		(pts
			(xy 278.13 140.97) (xy 306.07 140.97)
		)
		(stroke
			(width 0)
			(type default)
		)
	)
	(wire
		(pts
			(xy 208.28 140.97) (xy 250.19 140.97)
		)
		(stroke
			(width 0)
			(type default)
		)
	)
	(bus
		(pts
			(xy 96.52 162.56) (xy 96.52 165.1)
		)
		(stroke
			(width 0)
			(type default)
		)
	)
	(wire
		(pts
			(xy 123.19 113.03) (xy 118.11 113.03)
		)
		(stroke
			(width 0)
			(type default)
		)
	)
	(wire
		(pts
			(xy 151.13 157.48) (xy 134.62 157.48)
		)
		(stroke
			(width 0)
			(type default)
		)
	)
	(label "HDMI_FPGA.CLK_P"
		(at 104.14 167.64 0)
		(effects
			(font
				(size 1.27 1.27)
			)
			(justify left bottom)
		)
	)
	(label "PI3HDX511F.SDA"
		(at 229.87 154.94 0)
		(effects
			(font
				(size 1.27 1.27)
			)
			(justify left bottom)
		)
	)
	(label "PI3HDX_C_CLK_P"
		(at 151.13 167.64 180)
		(effects
			(font
				(size 1.27 1.27)
			)
			(justify right bottom)
		)
	)
	(label "HDMI0.TX0_P"
		(at 306.07 140.97 180)
		(effects
			(font
				(size 1.27 1.27)
			)
			(justify right bottom)
		)
	)
	(label "PI3HDX_C_TX0_P"
		(at 208.28 140.97 0)
		(effects
			(font
				(size 1.27 1.27)
			)
			(justify left bottom)
		)
	)
	(label "HDMI_FPGA.TX2_P"
		(at 103.505 152.4 0)
		(effects
			(font
				(size 1.27 1.27)
			)
			(justify left bottom)
		)
	)
	(label "PI3HDX_C_CLK_N"
		(at 151.13 165.1 180)
		(effects
			(font
				(size 1.27 1.27)
			)
			(justify right bottom)
		)
	)
	(label "HDMI_3V3"
		(at 254 115.57 180)
		(effects
			(font
				(size 1.27 1.27)
			)
			(justify right bottom)
		)
	)
	(label "HDMI_FPGA.TX0_P"
		(at 103.505 162.56 0)
		(effects
			(font
				(size 1.27 1.27)
			)
			(justify left bottom)
		)
	)
	(label "PI3HDX_C_TX1_P"
		(at 151.13 157.48 180)
		(effects
			(font
				(size 1.27 1.27)
			)
			(justify right bottom)
		)
	)
	(label "HDMI0.CLK_N"
		(at 306.07 148.59 180)
		(effects
			(font
				(size 1.27 1.27)
			)
			(justify right bottom)
		)
	)
	(label "PI3HDX_C_TX1_N"
		(at 208.28 138.43 0)
		(effects
			(font
				(size 1.27 1.27)
			)
			(justify left bottom)
		)
	)
	(label "PI3HDX_C_TX0_N"
		(at 208.28 143.51 0)
		(effects
			(font
				(size 1.27 1.27)
			)
			(justify left bottom)
		)
	)
	(label "HDMI_FPGA.TX0_N"
		(at 103.505 160.02 0)
		(effects
			(font
				(size 1.27 1.27)
			)
			(justify left bottom)
		)
	)
	(label "PI3HDX_C_TX1_P"
		(at 208.28 135.89 0)
		(effects
			(font
				(size 1.27 1.27)
			)
			(justify left bottom)
		)
	)
	(label "PI3HDX_C_TX2_P"
		(at 208.28 130.81 0)
		(effects
			(font
				(size 1.27 1.27)
			)
			(justify left bottom)
		)
	)
	(label "HDMI0.CLK_P"
		(at 306.07 146.05 180)
		(effects
			(font
				(size 1.27 1.27)
			)
			(justify right bottom)
		)
	)
	(label "HDMI_3V3"
		(at 133.35 99.06 180)
		(effects
			(font
				(size 1.27 1.27)
			)
			(justify right bottom)
		)
	)
	(label "HDMI_FPGA.TX1_N"
		(at 103.505 154.94 0)
		(effects
			(font
				(size 1.27 1.27)
			)
			(justify left bottom)
		)
	)
	(label "HDMI0.SCL"
		(at 327.025 157.48 0)
		(effects
			(font
				(size 1.27 1.27)
			)
			(justify left bottom)
		)
	)
	(label "HDMI0.TX1_N"
		(at 306.07 138.43 180)
		(effects
			(font
				(size 1.27 1.27)
			)
			(justify right bottom)
		)
	)
	(label "HDMI_FPGA.CLK_N"
		(at 104.14 165.1 0)
		(effects
			(font
				(size 1.27 1.27)
			)
			(justify left bottom)
		)
	)
	(label "PI3HDX_C_TX0_P"
		(at 151.13 162.56 180)
		(effects
			(font
				(size 1.27 1.27)
			)
			(justify right bottom)
		)
	)
	(label "HDMI_FPGA.TX1_P"
		(at 103.505 157.48 0)
		(effects
			(font
				(size 1.27 1.27)
			)
			(justify left bottom)
		)
	)
	(label "HDMI0.TX0_N"
		(at 306.07 143.51 180)
		(effects
			(font
				(size 1.27 1.27)
			)
			(justify right bottom)
		)
	)
	(label "PI3HDX_C_TX2_P"
		(at 151.13 152.4 180)
		(effects
			(font
				(size 1.27 1.27)
			)
			(justify right bottom)
		)
	)
	(label "PI3HDX_C_TX2_N"
		(at 151.13 149.86 180)
		(effects
			(font
				(size 1.27 1.27)
			)
			(justify right bottom)
		)
	)
	(label "PI3HDX_C_TX0_N"
		(at 151.13 160.02 180)
		(effects
			(font
				(size 1.27 1.27)
			)
			(justify right bottom)
		)
	)
	(label "PI3HDX_C_TX1_N"
		(at 151.13 154.94 180)
		(effects
			(font
				(size 1.27 1.27)
			)
			(justify right bottom)
		)
	)
	(label "HDMI0.SDA"
		(at 327.025 154.94 0)
		(effects
			(font
				(size 1.27 1.27)
			)
			(justify left bottom)
		)
	)
	(label "PI3HDX_C_TX2_N"
		(at 208.28 133.35 0)
		(effects
			(font
				(size 1.27 1.27)
			)
			(justify left bottom)
		)
	)
	(label "PI3HDX_C_CLK_P"
		(at 208.28 146.05 0)
		(effects
			(font
				(size 1.27 1.27)
			)
			(justify left bottom)
		)
	)
	(label "PI3HDX_C_CLK_N"
		(at 208.28 148.59 0)
		(effects
			(font
				(size 1.27 1.27)
			)
			(justify left bottom)
		)
	)
	(label "HDMI_FPGA.TX2_N"
		(at 103.505 149.86 0)
		(effects
			(font
				(size 1.27 1.27)
			)
			(justify left bottom)
		)
	)
	(label "HDMI0.TX2_N"
		(at 306.07 133.35 180)
		(effects
			(font
				(size 1.27 1.27)
			)
			(justify right bottom)
		)
	)
	(label "HDMI0.TX1_P"
		(at 306.07 135.89 180)
		(effects
			(font
				(size 1.27 1.27)
			)
			(justify right bottom)
		)
	)
	(label "HDMI0.TX2_P"
		(at 306.07 130.81 180)
		(effects
			(font
				(size 1.27 1.27)
			)
			(justify right bottom)
		)
	)
	(label "PI3HDX511F.SCL"
		(at 229.87 157.48 0)
		(effects
			(font
				(size 1.27 1.27)
			)
			(justify left bottom)
		)
	)
	(global_label "HDMI0_HOTPLUG"
		(shape input)
		(at 288.29 152.4 0)
		(fields_autoplaced yes)
		(effects
			(font
				(size 1.27 1.27)
			)
			(justify left)
		)
		(property "Intersheetrefs" "${INTERSHEET_REFS}"
			(at 306.6362 152.4 0)
			(effects
				(font
					(size 1.27 1.27)
				)
				(justify left)
			)
		)
	)
	(global_label "PI3HDX511F_HOTPLUG"
		(shape input)
		(at 228.6 152.4 180)
		(fields_autoplaced yes)
		(effects
			(font
				(size 1.27 1.27)
			)
			(justify right)
		)
		(property "Intersheetrefs" "${INTERSHEET_REFS}"
			(at 204.5086 152.4 0)
			(effects
				(font
					(size 1.27 1.27)
				)
				(justify right)
			)
		)
	)
	(hierarchical_label "HDMI0{I^{2}C}"
		(shape bidirectional)
		(at 342.9 149.86 0)
		(effects
			(font
				(size 1.27 1.27)
			)
			(justify left)
		)
	)
	(hierarchical_label "HDMI0{HDMI}"
		(shape bidirectional)
		(at 311.15 125.73 0)
		(effects
			(font
				(size 1.27 1.27)
			)
			(justify left)
		)
	)
	(hierarchical_label "HDMI_FPGA{HDMI}"
		(shape bidirectional)
		(at 92.71 144.78 180)
		(effects
			(font
				(size 1.27 1.27)
			)
			(justify right)
		)
	)
	(hierarchical_label "PI3HDX511F{I^{2}C}"
		(shape bidirectional)
		(at 193.04 149.86 180)
		(effects
			(font
				(size 1.27 1.27)
			)
			(justify right)
		)
	)
	(symbol
		(lib_id "antmicropower:+3V3")
		(at 100.33 97.79 0)
		(unit 1)
		(exclude_from_sim no)
		(in_bom yes)
		(on_board yes)
		(dnp no)
		(fields_autoplaced yes)
		(property "Reference" "#PWR0156"
			(at 115.57 97.79 0)
			(effects
				(font
					(size 1.27 1.27)
					(thickness 0.15)
				)
				(justify left bottom)
				(hide yes)
			)
		)
		(property "Value" "+3V3"
			(at 100.33 92.71 0)
			(effects
				(font
					(size 1.27 1.27)
					(thickness 0.15)
				)
			)
		)
		(property "Footprint" ""
			(at 115.57 105.41 0)
			(effects
				(font
					(size 1.27 1.27)
					(thickness 0.15)
				)
				(justify left bottom)
				(hide yes)
			)
		)
		(property "Datasheet" ""
			(at 115.57 107.95 0)
			(effects
				(font
					(size 1.27 1.27)
					(thickness 0.15)
				)
				(justify left bottom)
				(hide yes)
			)
		)
		(property "Description" ""
			(at 100.33 97.79 0)
			(effects
				(font
					(size 1.27 1.27)
				)
				(hide yes)
			)
		)
		(property "Author" "Antmicro"
			(at 115.57 100.33 0)
			(effects
				(font
					(size 1.27 1.27)
					(thickness 0.15)
				)
				(justify left bottom)
				(hide yes)
			)
		)
		(property "License" "Apache-2.0"
			(at 115.57 102.87 0)
			(effects
				(font
					(size 1.27 1.27)
					(thickness 0.15)
				)
				(justify left bottom)
				(hide yes)
			)
		)
		(pin "1"
		)
		(instances
			(project "polarfire-som"
				(path ""
					(reference "#PWR0156")
					(unit 1)
				)
			)
		)
	)
	(symbol
		(lib_id "antmicroTestPoints:TP_0.75mm_SMD")
		(at 283.21 121.92 0)
		(mirror x)
		(unit 1)
		(exclude_from_sim no)
		(in_bom no)
		(on_board yes)
		(dnp no)
		(property "Reference" "TP17"
			(at 290.83 121.92 0)
			(effects
				(font
					(size 1.27 1.27)
					(thickness 0.15)
				)
			)
		)
		(property "Value" "TP_0.75mm_SMD"
			(at 294.005 118.11 0)
			(effects
				(font
					(size 1.27 1.27)
					(thickness 0.15)
				)
				(justify left bottom)
				(hide yes)
			)
		)
		(property "Footprint" "antmicro-footprints:TP_SMD_0.75mm"
			(at 294.005 115.57 0)
			(effects
				(font
					(size 1.27 1.27)
					(thickness 0.15)
				)
				(justify left bottom)
				(hide yes)
			)
		)
		(property "Datasheet" ""
			(at 300.99 109.22 0)
			(effects
				(font
					(size 1.27 1.27)
					(thickness 0.15)
				)
				(justify left bottom)
				(hide yes)
			)
		)
		(property "Description" "SMT test point"
			(at 283.21 121.92 0)
			(effects
				(font
					(size 1.27 1.27)
				)
				(hide yes)
			)
		)
		(property "MPN" ""
			(at 294.005 110.49 0)
			(effects
				(font
					(size 1.27 1.27)
					(thickness 0.15)
				)
				(justify left bottom)
				(hide yes)
			)
		)
		(property "Manufacturer" ""
			(at 294.005 115.57 0)
			(effects
				(font
					(size 1.27 1.27)
					(thickness 0.15)
				)
				(justify left bottom)
				(hide yes)
			)
		)
		(property "Author" "Antmicro"
			(at 294.005 113.03 0)
			(effects
				(font
					(size 1.27 1.27)
					(thickness 0.15)
				)
				(justify left bottom)
				(hide yes)
			)
		)
		(property "License" "Apache-2.0"
			(at 294.005 110.49 0)
			(effects
				(font
					(size 1.27 1.27)
					(thickness 0.15)
				)
				(justify left bottom)
				(hide yes)
			)
		)
		(property "Public" "False"
			(at 293.37 107.95 0)
			(effects
				(font
					(size 1.27 1.27)
				)
				(justify left bottom)
				(hide yes)
			)
		)
		(pin "1"
		)
		(instances
			(project "polarfire-som"
				(path ""
					(reference "TP17")
					(unit 1)
				)
			)
		)
	)
	(symbol
		(lib_id "antmicroCapacitors0402:C_100n_0402")
		(at 123.19 102.87 270)
		(unit 1)
		(exclude_from_sim no)
		(in_bom yes)
		(on_board yes)
		(dnp no)
		(property "Reference" "C187"
			(at 121.92 109.22 0)
			(effects
				(font
					(size 1.27 1.27)
					(thickness 0.15)
				)
			)
		)
		(property "Value" "C_100n_0402"
			(at 113.03 123.19 0)
			(effects
				(font
					(size 1.27 1.27)
					(thickness 0.15)
				)
				(justify left bottom)
				(hide yes)
			)
		)
		(property "Footprint" "antmicro-footprints:C_0402_1005Metric"
			(at 110.49 123.19 0)
			(effects
				(font
					(size 1.27 1.27)
					(thickness 0.15)
				)
				(justify left bottom)
				(hide yes)
			)
		)
		(property "Datasheet" "https://www.murata.com/products/productdetail?partno=GRM155R61H104KE14%23"
			(at 107.95 123.19 0)
			(effects
				(font
					(size 1.27 1.27)
					(thickness 0.15)
				)
				(justify left bottom)
				(hide yes)
			)
		)
		(property "Description" "SMD Multilayer Ceramic Capacitor, 0.1 µF, 50 V, 0402 [1005 Metric], ± 10%, X5R, GRM Series"
			(at 123.19 102.87 0)
			(effects
				(font
					(size 1.27 1.27)
				)
				(hide yes)
			)
		)
		(property "MPN" "GRM155R61H104KE14D"
			(at 105.41 123.19 0)
			(effects
				(font
					(size 1.27 1.27)
					(thickness 0.15)
				)
				(justify left bottom)
				(hide yes)
			)
		)
		(property "Manufacturer" "Murata"
			(at 102.87 123.19 0)
			(effects
				(font
					(size 1.27 1.27)
					(thickness 0.15)
				)
				(justify left bottom)
				(hide yes)
			)
		)
		(property "License" "Apache-2.0"
			(at 100.33 123.19 0)
			(effects
				(font
					(size 1.27 1.27)
					(thickness 0.15)
				)
				(justify left bottom)
				(hide yes)
			)
		)
		(property "Author" "Antmicro"
			(at 97.79 123.19 0)
			(effects
				(font
					(size 1.27 1.27)
					(thickness 0.15)
				)
				(justify left bottom)
				(hide yes)
			)
		)
		(property "Val" "100n"
			(at 120.65 99.06 0)
			(effects
				(font
					(size 1.27 1.27)
					(thickness 0.15)
				)
				(justify left bottom)
			)
		)
		(property "Voltage" "50V"
			(at 95.25 123.19 0)
			(effects
				(font
					(size 1.27 1.27)
				)
				(justify left bottom)
				(hide yes)
			)
		)
		(property "Dielectric" "X5R"
			(at 92.71 123.19 0)
			(effects
				(font
					(size 1.27 1.27)
				)
				(justify left bottom)
				(hide yes)
			)
		)
		(property "Public" ""
			(at 90.17 123.19 0)
			(effects
				(font
					(size 1.27 1.27)
				)
				(justify left bottom)
				(hide yes)
			)
		)
		(pin "2"
		)
		(pin "1"
		)
		(instances
			(project "polarfire-som"
				(path ""
					(reference "C187")
					(unit 1)
				)
			)
		)
	)
	(symbol
		(lib_id "antmicroResistorNetworksArrays:4x0R_0402_array")
		(at 124.46 149.86 0)
		(unit 1)
		(exclude_from_sim no)
		(in_bom yes)
		(on_board yes)
		(dnp no)
		(property "Reference" "R107"
			(at 129.54 144.78 0)
			(effects
				(font
					(size 1.27 1.27)
					(thickness 0.15)
				)
			)
		)
		(property "Value" "4x0R_0402_array"
			(at 149.86 156.21 0)
			(effects
				(font
					(size 1.27 1.27)
					(thickness 0.15)
				)
				(justify left bottom)
				(hide yes)
			)
		)
		(property "Footprint" "antmicro-footprints:4x0R_0402_array_EXB28V"
			(at 149.86 161.29 0)
			(effects
				(font
					(size 1.27 1.27)
					(thickness 0.15)
				)
				(justify left bottom)
				(hide yes)
			)
		)
		(property "Datasheet" "https://industrial.panasonic.com/cdbs/www-data/pdf/AOC0000/AOC0000C14.pdf"
			(at 149.86 163.83 0)
			(effects
				(font
					(size 1.27 1.27)
					(thickness 0.15)
				)
				(justify left bottom)
				(hide yes)
			)
		)
		(property "Description" "Zero Ohm Network Resistor, Jumper, 0402 [1005 Metric], Thick Film, Isolated, Convex, 4 Resistors"
			(at 124.46 149.86 0)
			(effects
				(font
					(size 1.27 1.27)
				)
				(hide yes)
			)
		)
		(property "MPN" "EXB28VR000X"
			(at 149.86 166.37 0)
			(effects
				(font
					(size 1.27 1.27)
					(thickness 0.15)
				)
				(justify left bottom)
				(hide yes)
			)
		)
		(property "Manufacturer" "Panasonic"
			(at 149.86 168.91 0)
			(effects
				(font
					(size 1.27 1.27)
					(thickness 0.15)
				)
				(justify left bottom)
				(hide yes)
			)
		)
		(property "Author" "Antmicro"
			(at 149.86 171.45 0)
			(effects
				(font
					(size 1.27 1.27)
					(thickness 0.15)
				)
				(justify left bottom)
				(hide yes)
			)
		)
		(property "License" "Apache-2.0"
			(at 149.86 173.99 0)
			(effects
				(font
					(size 1.27 1.27)
					(thickness 0.15)
				)
				(justify left bottom)
				(hide yes)
			)
		)
		(property "Val" "4x0R_0402"
			(at 129.54 147.32 0)
			(effects
				(font
					(size 1.27 1.27)
				)
			)
		)
		(pin "5"
		)
		(pin "7"
		)
		(pin "3"
		)
		(pin "4"
		)
		(pin "6"
		)
		(pin "8"
		)
		(pin "2"
		)
		(pin "1"
		)
		(instances
			(project ""
				(path ""
					(reference "R107")
					(unit 1)
				)
			)
		)
	)
	(symbol
		(lib_id "antmicropower:PWR_FLAG")
		(at 241.3 124.46 0)
		(unit 1)
		(exclude_from_sim no)
		(in_bom yes)
		(on_board yes)
		(dnp no)
		(property "Reference" "#FLG021"
			(at 241.3 122.555 0)
			(effects
				(font
					(size 1.27 1.27)
				)
				(hide yes)
			)
		)
		(property "Value" "PWR_FLAG"
			(at 241.3 116.84 90)
			(effects
				(font
					(size 1.27 1.27)
				)
			)
		)
		(property "Footprint" ""
			(at 241.3 124.46 0)
			(effects
				(font
					(size 1.27 1.27)
				)
				(hide yes)
			)
		)
		(property "Datasheet" ""
			(at 241.3 124.46 0)
			(effects
				(font
					(size 1.27 1.27)
				)
				(hide yes)
			)
		)
		(property "Description" ""
			(at 241.3 124.46 0)
			(effects
				(font
					(size 1.27 1.27)
				)
				(hide yes)
			)
		)
		(pin "1"
		)
		(instances
			(project "polarfire-som"
				(path ""
					(reference "#FLG021")
					(unit 1)
				)
			)
		)
	)
	(symbol
		(lib_id "antmicroInterfaceDriversReceiversTransceivers:PI3HDX511DZLE")
		(at 250.19 121.92 0)
		(unit 1)
		(exclude_from_sim no)
		(in_bom yes)
		(on_board yes)
		(dnp no)
		(fields_autoplaced yes)
		(property "Reference" "U15"
			(at 264.16 114.3 0)
			(effects
				(font
					(size 1.27 1.27)
					(thickness 0.15)
				)
			)
		)
		(property "Value" "PI3HDX511DZLE"
			(at 300.99 127 0)
			(effects
				(font
					(size 1.27 1.27)
					(thickness 0.15)
				)
				(justify left bottom)
				(hide yes)
			)
		)
		(property "Footprint" "antmicro-footprints:TQFN-30-1EP_2.5x4.5mm_P0.4mm_Layout5x10"
			(at 300.99 129.54 0)
			(effects
				(font
					(size 1.27 1.27)
					(thickness 0.15)
				)
				(justify left bottom)
				(hide yes)
			)
		)
		(property "Datasheet" "https://eu.mouser.com/datasheet/2/115/diodes_inc_diod-s-a0004145302-1-1749206.pdf"
			(at 300.99 132.08 0)
			(effects
				(font
					(size 1.27 1.27)
					(thickness 0.15)
				)
				(justify left bottom)
				(hide yes)
			)
		)
		(property "Description" "Video ICs Active HDMI TQFN-30"
			(at 250.19 121.92 0)
			(effects
				(font
					(size 1.27 1.27)
				)
				(hide yes)
			)
		)
		(property "MPN" "PI3HDX511DZLE"
			(at 264.16 116.84 0)
			(effects
				(font
					(size 1.27 1.27)
					(thickness 0.15)
				)
			)
		)
		(property "Manufacturer" "Diodes Incorporated"
			(at 300.99 134.62 0)
			(effects
				(font
					(size 1.27 1.27)
					(thickness 0.15)
				)
				(justify left bottom)
				(hide yes)
			)
		)
		(property "Author" "Antmicro"
			(at 300.99 137.16 0)
			(effects
				(font
					(size 1.27 1.27)
					(thickness 0.15)
				)
				(justify left bottom)
				(hide yes)
			)
		)
		(property "License" "Apache-2.0"
			(at 300.99 139.7 0)
			(effects
				(font
					(size 1.27 1.27)
					(thickness 0.15)
				)
				(justify left bottom)
				(hide yes)
			)
		)
		(pin "25"
		)
		(pin "26"
		)
		(pin "27"
		)
		(pin "23"
		)
		(pin "18"
		)
		(pin "24"
		)
		(pin "30"
		)
		(pin "11"
		)
		(pin "31"
		)
		(pin "7"
		)
		(pin "21"
		)
		(pin "2"
		)
		(pin "4"
		)
		(pin "17"
		)
		(pin "20"
		)
		(pin "9"
		)
		(pin "29"
		)
		(pin "8"
		)
		(pin "3"
		)
		(pin "28"
		)
		(pin "10"
		)
		(pin "19"
		)
		(pin "6"
		)
		(pin "22"
		)
		(pin "15"
		)
		(pin "14"
		)
		(pin "16"
		)
		(pin "1"
		)
		(pin "12"
		)
		(pin "5"
		)
		(pin "13"
		)
		(instances
			(project "polarfire-som"
				(path ""
					(reference "U15")
					(unit 1)
				)
			)
		)
	)
	(symbol
		(lib_id "antmicroResistorNetworksArrays:4x0R_0402_array")
		(at 124.46 160.02 0)
		(unit 1)
		(exclude_from_sim no)
		(in_bom yes)
		(on_board yes)
		(dnp no)
		(property "Reference" "R108"
			(at 129.54 170.18 0)
			(effects
				(font
					(size 1.27 1.27)
					(thickness 0.15)
				)
			)
		)
		(property "Value" "4x0R_0402_array"
			(at 149.86 166.37 0)
			(effects
				(font
					(size 1.27 1.27)
					(thickness 0.15)
				)
				(justify left bottom)
				(hide yes)
			)
		)
		(property "Footprint" "antmicro-footprints:4x0R_0402_array_EXB28V"
			(at 149.86 171.45 0)
			(effects
				(font
					(size 1.27 1.27)
					(thickness 0.15)
				)
				(justify left bottom)
				(hide yes)
			)
		)
		(property "Datasheet" "https://industrial.panasonic.com/cdbs/www-data/pdf/AOC0000/AOC0000C14.pdf"
			(at 149.86 173.99 0)
			(effects
				(font
					(size 1.27 1.27)
					(thickness 0.15)
				)
				(justify left bottom)
				(hide yes)
			)
		)
		(property "Description" "Zero Ohm Network Resistor, Jumper, 0402 [1005 Metric], Thick Film, Isolated, Convex, 4 Resistors"
			(at 124.46 160.02 0)
			(effects
				(font
					(size 1.27 1.27)
				)
				(hide yes)
			)
		)
		(property "MPN" "EXB28VR000X"
			(at 149.86 176.53 0)
			(effects
				(font
					(size 1.27 1.27)
					(thickness 0.15)
				)
				(justify left bottom)
				(hide yes)
			)
		)
		(property "Manufacturer" "Panasonic"
			(at 149.86 179.07 0)
			(effects
				(font
					(size 1.27 1.27)
					(thickness 0.15)
				)
				(justify left bottom)
				(hide yes)
			)
		)
		(property "Author" "Antmicro"
			(at 149.86 181.61 0)
			(effects
				(font
					(size 1.27 1.27)
					(thickness 0.15)
				)
				(justify left bottom)
				(hide yes)
			)
		)
		(property "License" "Apache-2.0"
			(at 149.86 184.15 0)
			(effects
				(font
					(size 1.27 1.27)
					(thickness 0.15)
				)
				(justify left bottom)
				(hide yes)
			)
		)
		(property "Val" "4x0R_0402"
			(at 129.54 172.72 0)
			(effects
				(font
					(size 1.27 1.27)
				)
			)
		)
		(pin "5"
		)
		(pin "7"
		)
		(pin "3"
		)
		(pin "4"
		)
		(pin "6"
		)
		(pin "8"
		)
		(pin "2"
		)
		(pin "1"
		)
		(instances
			(project "polarfire-som"
				(path ""
					(reference "R108")
					(unit 1)
				)
			)
		)
	)
	(symbol
		(lib_id "antmicroCapacitors0402:C_10u_10V_0402")
		(at 128.27 107.95 90)
		(unit 1)
		(exclude_from_sim no)
		(in_bom yes)
		(on_board yes)
		(dnp no)
		(property "Reference" "C188"
			(at 127 106.68 0)
			(effects
				(font
					(size 1.27 1.27)
					(thickness 0.15)
				)
				(justify right)
			)
		)
		(property "Value" "C_10u_10V_0402"
			(at 138.43 87.63 0)
			(effects
				(font
					(size 1.27 1.27)
					(thickness 0.15)
				)
				(justify left bottom)
				(hide yes)
			)
		)
		(property "Footprint" "antmicro-footprints:C_0402_1005Metric"
			(at 140.97 87.63 0)
			(effects
				(font
					(size 1.27 1.27)
					(thickness 0.15)
				)
				(justify left bottom)
				(hide yes)
			)
		)
		(property "Datasheet" "https://www.murata.com/products/productdetail?partno=GRM155R61A106ME11%23"
			(at 143.51 87.63 0)
			(effects
				(font
					(size 1.27 1.27)
					(thickness 0.15)
				)
				(justify left bottom)
				(hide yes)
			)
		)
		(property "Description" "Multilayer Ceramic Capacitors MLCC - SMD/SMT 10 uF 10 VDC 20% 0402 X5R"
			(at 128.27 107.95 0)
			(effects
				(font
					(size 1.27 1.27)
				)
				(hide yes)
			)
		)
		(property "MPN" "GRM155R61A106ME11D"
			(at 146.05 87.63 0)
			(effects
				(font
					(size 1.27 1.27)
					(thickness 0.15)
				)
				(justify left bottom)
				(hide yes)
			)
		)
		(property "Manufacturer" "Murata"
			(at 148.59 87.63 0)
			(effects
				(font
					(size 1.27 1.27)
					(thickness 0.15)
				)
				(justify left bottom)
				(hide yes)
			)
		)
		(property "License" "Apache-2.0"
			(at 151.13 87.63 0)
			(effects
				(font
					(size 1.27 1.27)
					(thickness 0.15)
				)
				(justify left bottom)
				(hide yes)
			)
		)
		(property "Author" "Antmicro"
			(at 153.67 87.63 0)
			(effects
				(font
					(size 1.27 1.27)
					(thickness 0.15)
				)
				(justify left bottom)
				(hide yes)
			)
		)
		(property "Val" "10u"
			(at 127 100.33 0)
			(effects
				(font
					(size 1.27 1.27)
					(thickness 0.15)
				)
				(justify right)
			)
		)
		(property "Voltage" "10V"
			(at 156.21 87.63 0)
			(effects
				(font
					(size 1.27 1.27)
				)
				(justify left bottom)
				(hide yes)
			)
		)
		(property "Dielectric" "X5R"
			(at 158.75 87.63 0)
			(effects
				(font
					(size 1.27 1.27)
				)
				(justify left bottom)
				(hide yes)
			)
		)
		(property "Public" ""
			(at 161.29 87.63 0)
			(effects
				(font
					(size 1.27 1.27)
				)
				(justify left bottom)
				(hide yes)
			)
		)
		(pin "1"
		)
		(pin "2"
		)
		(instances
			(project "polarfire-som"
				(path ""
					(reference "C188")
					(unit 1)
				)
			)
		)
	)
	(symbol
		(lib_id "antmicropower:+5V")
		(at 321.31 135.89 0)
		(unit 1)
		(exclude_from_sim no)
		(in_bom yes)
		(on_board yes)
		(dnp no)
		(property "Reference" "#PWR0207"
			(at 336.55 138.43 0)
			(effects
				(font
					(size 1.27 1.27)
					(thickness 0.15)
				)
				(justify left bottom)
				(hide yes)
			)
		)
		(property "Value" "+5V"
			(at 321.31 132.08 0)
			(effects
				(font
					(size 1.27 1.27)
					(thickness 0.15)
				)
			)
		)
		(property "Footprint" ""
			(at 336.55 143.51 0)
			(effects
				(font
					(size 1.27 1.27)
					(thickness 0.15)
				)
				(justify left bottom)
				(hide yes)
			)
		)
		(property "Datasheet" ""
			(at 336.55 146.05 0)
			(effects
				(font
					(size 1.27 1.27)
					(thickness 0.15)
				)
				(justify left bottom)
				(hide yes)
			)
		)
		(property "Description" ""
			(at 321.31 135.89 0)
			(effects
				(font
					(size 1.27 1.27)
				)
				(hide yes)
			)
		)
		(property "Author" "Antmicro"
			(at 336.55 143.51 0)
			(effects
				(font
					(size 1.27 1.27)
					(thickness 0.15)
				)
				(justify left bottom)
				(hide yes)
			)
		)
		(property "License" "Apache-2.0"
			(at 336.55 146.05 0)
			(effects
				(font
					(size 1.27 1.27)
					(thickness 0.15)
				)
				(justify left bottom)
				(hide yes)
			)
		)
		(pin "1"
		)
		(instances
			(project "polarfire-som"
				(path ""
					(reference "#PWR0207")
					(unit 1)
				)
			)
		)
	)
	(symbol
		(lib_id "antmicropower:GND")
		(at 229.87 124.46 270)
		(unit 1)
		(exclude_from_sim no)
		(in_bom yes)
		(on_board yes)
		(dnp no)
		(property "Reference" "#PWR0167"
			(at 227.33 133.35 0)
			(effects
				(font
					(size 1.27 1.27)
					(thickness 0.15)
				)
				(justify left bottom)
				(hide yes)
			)
		)
		(property "Value" "GND"
			(at 228.6 121.92 90)
			(effects
				(font
					(size 1.27 1.27)
					(thickness 0.15)
				)
			)
		)
		(property "Footprint" ""
			(at 222.25 133.35 0)
			(effects
				(font
					(size 1.27 1.27)
					(thickness 0.15)
				)
				(justify left bottom)
				(hide yes)
			)
		)
		(property "Datasheet" ""
			(at 217.17 133.35 0)
			(effects
				(font
					(size 1.27 1.27)
					(thickness 0.15)
				)
				(justify left bottom)
				(hide yes)
			)
		)
		(property "Description" ""
			(at 229.87 124.46 0)
			(effects
				(font
					(size 1.27 1.27)
				)
				(hide yes)
			)
		)
		(property "Author" "Antmicro"
			(at 222.25 133.35 0)
			(effects
				(font
					(size 1.27 1.27)
					(thickness 0.15)
				)
				(justify left bottom)
				(hide yes)
			)
		)
		(property "License" "Apache-2.0"
			(at 219.71 133.35 0)
			(effects
				(font
					(size 1.27 1.27)
					(thickness 0.15)
				)
				(justify left bottom)
				(hide yes)
			)
		)
		(pin "1"
		)
		(instances
			(project "polarfire-som"
				(path ""
					(reference "#PWR0167")
					(unit 1)
				)
			)
		)
	)
	(symbol
		(lib_id "antmicroTestPoints:TP_0.75mm_SMD")
		(at 283.21 124.46 0)
		(mirror x)
		(unit 1)
		(exclude_from_sim no)
		(in_bom no)
		(on_board yes)
		(dnp no)
		(property "Reference" "TP19"
			(at 290.83 124.46 0)
			(effects
				(font
					(size 1.27 1.27)
					(thickness 0.15)
				)
			)
		)
		(property "Value" "TP_0.75mm_SMD"
			(at 294.005 120.65 0)
			(effects
				(font
					(size 1.27 1.27)
					(thickness 0.15)
				)
				(justify left bottom)
				(hide yes)
			)
		)
		(property "Footprint" "antmicro-footprints:TP_SMD_0.75mm"
			(at 294.005 118.11 0)
			(effects
				(font
					(size 1.27 1.27)
					(thickness 0.15)
				)
				(justify left bottom)
				(hide yes)
			)
		)
		(property "Datasheet" ""
			(at 300.99 111.76 0)
			(effects
				(font
					(size 1.27 1.27)
					(thickness 0.15)
				)
				(justify left bottom)
				(hide yes)
			)
		)
		(property "Description" "SMT test point"
			(at 283.21 124.46 0)
			(effects
				(font
					(size 1.27 1.27)
				)
				(hide yes)
			)
		)
		(property "MPN" ""
			(at 294.005 113.03 0)
			(effects
				(font
					(size 1.27 1.27)
					(thickness 0.15)
				)
				(justify left bottom)
				(hide yes)
			)
		)
		(property "Manufacturer" ""
			(at 294.005 118.11 0)
			(effects
				(font
					(size 1.27 1.27)
					(thickness 0.15)
				)
				(justify left bottom)
				(hide yes)
			)
		)
		(property "Author" "Antmicro"
			(at 294.005 115.57 0)
			(effects
				(font
					(size 1.27 1.27)
					(thickness 0.15)
				)
				(justify left bottom)
				(hide yes)
			)
		)
		(property "License" "Apache-2.0"
			(at 294.005 113.03 0)
			(effects
				(font
					(size 1.27 1.27)
					(thickness 0.15)
				)
				(justify left bottom)
				(hide yes)
			)
		)
		(property "Public" "False"
			(at 293.37 110.49 0)
			(effects
				(font
					(size 1.27 1.27)
				)
				(justify left bottom)
				(hide yes)
			)
		)
		(pin "1"
		)
		(instances
			(project "polarfire-som"
				(path ""
					(reference "TP19")
					(unit 1)
				)
			)
		)
	)
	(symbol
		(lib_id "antmicroCapacitors0402:C_4u7_0402")
		(at 232.41 124.46 0)
		(unit 1)
		(exclude_from_sim no)
		(in_bom yes)
		(on_board yes)
		(dnp no)
		(fields_autoplaced yes)
		(property "Reference" "C226"
			(at 234.9563 118.11 0)
			(effects
				(font
					(size 1.27 1.27)
					(thickness 0.15)
				)
			)
		)
		(property "Value" "C_4u7_0402"
			(at 252.73 134.62 0)
			(effects
				(font
					(size 1.27 1.27)
					(thickness 0.15)
				)
				(justify left bottom)
				(hide yes)
			)
		)
		(property "Footprint" "antmicro-footprints:C_0402_1005Metric"
			(at 252.73 137.16 0)
			(effects
				(font
					(size 1.27 1.27)
					(thickness 0.15)
				)
				(justify left bottom)
				(hide yes)
			)
		)
		(property "Datasheet" "https://www.murata.com/products/productdetail?partno=GRM155R61A475MEAA%23"
			(at 252.73 139.7 0)
			(effects
				(font
					(size 1.27 1.27)
					(thickness 0.15)
				)
				(justify left bottom)
				(hide yes)
			)
		)
		(property "Description" "SMD Multilayer Ceramic Capacitor, 4.7 µF, 10 V, 0402 [1005 Metric], ± 20%, X5R, GRM Series"
			(at 232.41 124.46 0)
			(effects
				(font
					(size 1.27 1.27)
				)
				(hide yes)
			)
		)
		(property "MPN" "GRM155R61A475MEAAD"
			(at 252.73 142.24 0)
			(effects
				(font
					(size 1.27 1.27)
					(thickness 0.15)
				)
				(justify left bottom)
				(hide yes)
			)
		)
		(property "Manufacturer" "Murata"
			(at 252.73 144.78 0)
			(effects
				(font
					(size 1.27 1.27)
					(thickness 0.15)
				)
				(justify left bottom)
				(hide yes)
			)
		)
		(property "License" "Apache-2.0"
			(at 252.73 147.32 0)
			(effects
				(font
					(size 1.27 1.27)
					(thickness 0.15)
				)
				(justify left bottom)
				(hide yes)
			)
		)
		(property "Author" "Antmicro"
			(at 252.73 149.86 0)
			(effects
				(font
					(size 1.27 1.27)
					(thickness 0.15)
				)
				(justify left bottom)
				(hide yes)
			)
		)
		(property "Val" "4u7"
			(at 234.9563 120.65 0)
			(effects
				(font
					(size 1.27 1.27)
					(thickness 0.15)
				)
			)
		)
		(property "Voltage" ""
			(at 252.73 152.4 0)
			(effects
				(font
					(size 1.27 1.27)
				)
				(justify left bottom)
				(hide yes)
			)
		)
		(property "Dielectric" ""
			(at 252.73 154.94 0)
			(effects
				(font
					(size 1.27 1.27)
				)
				(justify left bottom)
				(hide yes)
			)
		)
		(property "Public" ""
			(at 252.73 157.48 0)
			(effects
				(font
					(size 1.27 1.27)
				)
				(justify left bottom)
				(hide yes)
			)
		)
		(pin "1"
		)
		(pin "2"
		)
		(instances
			(project "polarfire-som"
				(path ""
					(reference "C226")
					(unit 1)
				)
			)
		)
	)
	(symbol
		(lib_id "antmicroResistors0402:R_2k2_0402")
		(at 321.31 146.05 270)
		(mirror x)
		(unit 1)
		(exclude_from_sim no)
		(in_bom yes)
		(on_board yes)
		(dnp no)
		(property "Reference" "R79"
			(at 323.85 142.24 90)
			(effects
				(font
					(size 1.27 1.27)
					(thickness 0.15)
				)
				(justify left)
			)
		)
		(property "Value" "R_2k2_0402"
			(at 308.61 125.73 0)
			(effects
				(font
					(size 1.27 1.27)
					(thickness 0.15)
				)
				(justify left bottom)
				(hide yes)
			)
		)
		(property "Footprint" "antmicro-footprints:R_0402_1005Metric"
			(at 306.07 125.73 0)
			(effects
				(font
					(size 1.27 1.27)
					(thickness 0.15)
				)
				(justify left bottom)
				(hide yes)
			)
		)
		(property "Datasheet" "https://www.bourns.com/docs/product-datasheets/cr.pdf"
			(at 303.53 125.73 0)
			(effects
				(font
					(size 1.27 1.27)
					(thickness 0.15)
				)
				(justify left bottom)
				(hide yes)
			)
		)
		(property "Description" "SMD Chip Resistor, 2.2 kohm, ± 1%, 62.5 mW, 0402 [1005 Metric], Thick Film, General Purpose"
			(at 321.31 146.05 0)
			(effects
				(font
					(size 1.27 1.27)
				)
				(hide yes)
			)
		)
		(property "MPN" "CR0402-FX-2201GLF"
			(at 300.99 125.73 0)
			(effects
				(font
					(size 1.27 1.27)
					(thickness 0.15)
				)
				(justify left bottom)
				(hide yes)
			)
		)
		(property "Manufacturer" "Bourns"
			(at 298.45 125.73 0)
			(effects
				(font
					(size 1.27 1.27)
					(thickness 0.15)
				)
				(justify left bottom)
				(hide yes)
			)
		)
		(property "License" "Apache-2.0"
			(at 295.91 125.73 0)
			(effects
				(font
					(size 1.27 1.27)
					(thickness 0.15)
				)
				(justify left bottom)
				(hide yes)
			)
		)
		(property "Author" "Antmicro"
			(at 293.37 125.73 0)
			(effects
				(font
					(size 1.27 1.27)
					(thickness 0.15)
				)
				(justify left bottom)
				(hide yes)
			)
		)
		(property "Val" "2k2"
			(at 323.85 144.78 90)
			(effects
				(font
					(size 1.27 1.27)
					(thickness 0.15)
				)
				(justify left)
			)
		)
		(property "Tolerance" "1%"
			(at 311.15 125.73 0)
			(effects
				(font
					(size 1.27 1.27)
				)
				(justify left bottom)
				(hide yes)
			)
		)
		(property "Public" ""
			(at 290.83 125.73 0)
			(effects
				(font
					(size 1.27 1.27)
				)
				(justify left bottom)
				(hide yes)
			)
		)
		(pin "1"
		)
		(pin "2"
		)
		(instances
			(project "polarfire-som"
				(path ""
					(reference "R79")
					(unit 1)
				)
			)
		)
	)
	(symbol
		(lib_id "antmicropower:GND")
		(at 133.35 116.84 0)
		(unit 1)
		(exclude_from_sim no)
		(in_bom yes)
		(on_board yes)
		(dnp no)
		(property "Reference" "#PWR0158"
			(at 142.24 119.38 0)
			(effects
				(font
					(size 1.27 1.27)
					(thickness 0.15)
				)
				(justify left bottom)
				(hide yes)
			)
		)
		(property "Value" "GND"
			(at 137.16 118.11 0)
			(effects
				(font
					(size 1.27 1.27)
					(thickness 0.15)
				)
			)
		)
		(property "Footprint" ""
			(at 142.24 124.46 0)
			(effects
				(font
					(size 1.27 1.27)
					(thickness 0.15)
				)
				(justify left bottom)
				(hide yes)
			)
		)
		(property "Datasheet" ""
			(at 142.24 129.54 0)
			(effects
				(font
					(size 1.27 1.27)
					(thickness 0.15)
				)
				(justify left bottom)
				(hide yes)
			)
		)
		(property "Description" ""
			(at 133.35 116.84 0)
			(effects
				(font
					(size 1.27 1.27)
				)
				(hide yes)
			)
		)
		(property "Author" "Antmicro"
			(at 142.24 124.46 0)
			(effects
				(font
					(size 1.27 1.27)
					(thickness 0.15)
				)
				(justify left bottom)
				(hide yes)
			)
		)
		(property "License" "Apache-2.0"
			(at 142.24 127 0)
			(effects
				(font
					(size 1.27 1.27)
					(thickness 0.15)
				)
				(justify left bottom)
				(hide yes)
			)
		)
		(pin "1"
		)
		(instances
			(project "polarfire-som"
				(path ""
					(reference "#PWR0158")
					(unit 1)
				)
			)
		)
	)
	(symbol
		(lib_id "antmicroFerriteBeadsandChips:FB_120Z_1.2A_TDK-MPZ_0402")
		(at 111.76 99.06 180)
		(unit 1)
		(exclude_from_sim no)
		(in_bom yes)
		(on_board yes)
		(dnp no)
		(fields_autoplaced yes)
		(property "Reference" "FB4"
			(at 109.2581 92.71 0)
			(effects
				(font
					(size 1.27 1.27)
					(thickness 0.15)
				)
			)
		)
		(property "Value" "FB_120Z_1.2A_TDK-MPZ_0402"
			(at 97.79 96.52 0)
			(effects
				(font
					(size 1.27 1.27)
					(thickness 0.15)
				)
				(justify left bottom)
				(hide yes)
			)
		)
		(property "Footprint" "antmicro-footprints:FB_0402_1005Metric"
			(at 97.79 91.44 0)
			(effects
				(font
					(size 1.27 1.27)
					(thickness 0.15)
				)
				(justify left bottom)
				(hide yes)
			)
		)
		(property "Datasheet" "https://product.tdk.com/en/search/emc/emc/beads/info?part_no=MPZ1005S121CT000"
			(at 97.79 88.9 0)
			(effects
				(font
					(size 1.27 1.27)
					(thickness 0.15)
				)
				(justify left bottom)
				(hide yes)
			)
		)
		(property "Description" "Ferrite Bead, 0402 [1005 Metric], 120 ohm, 1.2A, MPZ, 0.06 ohm, ± 25%, DC Power line"
			(at 111.76 99.06 0)
			(effects
				(font
					(size 1.27 1.27)
				)
				(hide yes)
			)
		)
		(property "Val" "120Z/1.2A"
			(at 109.2581 95.25 0)
			(effects
				(font
					(size 1.27 1.27)
				)
			)
		)
		(property "MPN" "MPZ1005S121CT000"
			(at 97.79 86.36 0)
			(effects
				(font
					(size 1.27 1.27)
					(thickness 0.15)
				)
				(justify left bottom)
				(hide yes)
			)
		)
		(property "Manufacturer" "TDK"
			(at 97.79 83.82 0)
			(effects
				(font
					(size 1.27 1.27)
					(thickness 0.15)
				)
				(justify left bottom)
				(hide yes)
			)
		)
		(property "Current" ""
			(at 91.44 76.2 0)
			(effects
				(font
					(size 1.27 1.27)
					(thickness 0.15)
				)
				(justify left bottom)
				(hide yes)
			)
		)
		(property "Author" "Antmicro"
			(at 97.79 81.28 0)
			(effects
				(font
					(size 1.27 1.27)
					(thickness 0.15)
				)
				(justify left bottom)
				(hide yes)
			)
		)
		(property "License" "Apache-2.0"
			(at 97.79 78.74 0)
			(effects
				(font
					(size 1.27 1.27)
					(thickness 0.15)
				)
				(justify left bottom)
				(hide yes)
			)
		)
		(property "Public" ""
			(at 91.44 83.82 0)
			(effects
				(font
					(size 1.27 1.27)
				)
				(justify left bottom)
				(hide yes)
			)
		)
		(pin "1"
		)
		(pin "2"
		)
		(instances
			(project "polarfire-som"
				(path ""
					(reference "FB4")
					(unit 1)
				)
			)
		)
	)
	(symbol
		(lib_id "antmicropower:PWR_FLAG")
		(at 134.62 99.06 270)
		(unit 1)
		(exclude_from_sim no)
		(in_bom yes)
		(on_board yes)
		(dnp no)
		(property "Reference" "#FLG024"
			(at 136.525 99.06 0)
			(effects
				(font
					(size 1.27 1.27)
				)
				(hide yes)
			)
		)
		(property "Value" "PWR_FLAG"
			(at 142.24 99.06 90)
			(effects
				(font
					(size 1.27 1.27)
				)
			)
		)
		(property "Footprint" ""
			(at 134.62 99.06 0)
			(effects
				(font
					(size 1.27 1.27)
				)
				(hide yes)
			)
		)
		(property "Datasheet" ""
			(at 134.62 99.06 0)
			(effects
				(font
					(size 1.27 1.27)
				)
				(hide yes)
			)
		)
		(property "Description" ""
			(at 134.62 99.06 0)
			(effects
				(font
					(size 1.27 1.27)
				)
				(hide yes)
			)
		)
		(pin "1"
		)
		(instances
			(project "polarfire-som"
				(path ""
					(reference "#FLG024")
					(unit 1)
				)
			)
		)
	)
	(symbol
		(lib_id "antmicropower:GND")
		(at 245.11 168.91 0)
		(unit 1)
		(exclude_from_sim no)
		(in_bom yes)
		(on_board yes)
		(dnp no)
		(fields_autoplaced yes)
		(property "Reference" "#PWR0173"
			(at 254 171.45 0)
			(effects
				(font
					(size 1.27 1.27)
					(thickness 0.15)
				)
				(justify left bottom)
				(hide yes)
			)
		)
		(property "Value" "GND"
			(at 245.11 173.99 0)
			(effects
				(font
					(size 1.27 1.27)
					(thickness 0.15)
				)
			)
		)
		(property "Footprint" ""
			(at 254 176.53 0)
			(effects
				(font
					(size 1.27 1.27)
					(thickness 0.15)
				)
				(justify left bottom)
				(hide yes)
			)
		)
		(property "Datasheet" ""
			(at 254 181.61 0)
			(effects
				(font
					(size 1.27 1.27)
					(thickness 0.15)
				)
				(justify left bottom)
				(hide yes)
			)
		)
		(property "Description" ""
			(at 245.11 168.91 0)
			(effects
				(font
					(size 1.27 1.27)
				)
				(hide yes)
			)
		)
		(property "Author" "Antmicro"
			(at 254 176.53 0)
			(effects
				(font
					(size 1.27 1.27)
					(thickness 0.15)
				)
				(justify left bottom)
				(hide yes)
			)
		)
		(property "License" "Apache-2.0"
			(at 254 179.07 0)
			(effects
				(font
					(size 1.27 1.27)
					(thickness 0.15)
				)
				(justify left bottom)
				(hide yes)
			)
		)
		(pin "1"
		)
		(instances
			(project "polarfire-som"
				(path ""
					(reference "#PWR0173")
					(unit 1)
				)
			)
		)
	)
	(symbol
		(lib_id "antmicroCapacitors0402:C_10u_10V_0402")
		(at 133.35 107.95 90)
		(unit 1)
		(exclude_from_sim no)
		(in_bom yes)
		(on_board yes)
		(dnp no)
		(property "Reference" "C189"
			(at 132.08 106.68 0)
			(effects
				(font
					(size 1.27 1.27)
					(thickness 0.15)
				)
				(justify right)
			)
		)
		(property "Value" "C_10u_10V_0402"
			(at 143.51 87.63 0)
			(effects
				(font
					(size 1.27 1.27)
					(thickness 0.15)
				)
				(justify left bottom)
				(hide yes)
			)
		)
		(property "Footprint" "antmicro-footprints:C_0402_1005Metric"
			(at 146.05 87.63 0)
			(effects
				(font
					(size 1.27 1.27)
					(thickness 0.15)
				)
				(justify left bottom)
				(hide yes)
			)
		)
		(property "Datasheet" "https://www.murata.com/products/productdetail?partno=GRM155R61A106ME11%23"
			(at 148.59 87.63 0)
			(effects
				(font
					(size 1.27 1.27)
					(thickness 0.15)
				)
				(justify left bottom)
				(hide yes)
			)
		)
		(property "Description" "Multilayer Ceramic Capacitors MLCC - SMD/SMT 10 uF 10 VDC 20% 0402 X5R"
			(at 133.35 107.95 0)
			(effects
				(font
					(size 1.27 1.27)
				)
				(hide yes)
			)
		)
		(property "MPN" "GRM155R61A106ME11D"
			(at 151.13 87.63 0)
			(effects
				(font
					(size 1.27 1.27)
					(thickness 0.15)
				)
				(justify left bottom)
				(hide yes)
			)
		)
		(property "Manufacturer" "Murata"
			(at 153.67 87.63 0)
			(effects
				(font
					(size 1.27 1.27)
					(thickness 0.15)
				)
				(justify left bottom)
				(hide yes)
			)
		)
		(property "License" "Apache-2.0"
			(at 156.21 87.63 0)
			(effects
				(font
					(size 1.27 1.27)
					(thickness 0.15)
				)
				(justify left bottom)
				(hide yes)
			)
		)
		(property "Author" "Antmicro"
			(at 158.75 87.63 0)
			(effects
				(font
					(size 1.27 1.27)
					(thickness 0.15)
				)
				(justify left bottom)
				(hide yes)
			)
		)
		(property "Val" "10u"
			(at 132.08 100.33 0)
			(effects
				(font
					(size 1.27 1.27)
					(thickness 0.15)
				)
				(justify right)
			)
		)
		(property "Voltage" "10V"
			(at 161.29 87.63 0)
			(effects
				(font
					(size 1.27 1.27)
				)
				(justify left bottom)
				(hide yes)
			)
		)
		(property "Dielectric" "X5R"
			(at 163.83 87.63 0)
			(effects
				(font
					(size 1.27 1.27)
				)
				(justify left bottom)
				(hide yes)
			)
		)
		(property "Public" ""
			(at 166.37 87.63 0)
			(effects
				(font
					(size 1.27 1.27)
				)
				(justify left bottom)
				(hide yes)
			)
		)
		(pin "1"
		)
		(pin "2"
		)
		(instances
			(project "polarfire-som"
				(path ""
					(reference "C189")
					(unit 1)
				)
			)
		)
	)
	(symbol
		(lib_id "antmicroResistors0402:R_2k2_0402")
		(at 317.5 146.05 90)
		(unit 1)
		(exclude_from_sim no)
		(in_bom yes)
		(on_board yes)
		(dnp no)
		(property "Reference" "R73"
			(at 314.96 142.24 90)
			(effects
				(font
					(size 1.27 1.27)
					(thickness 0.15)
				)
				(justify left)
			)
		)
		(property "Value" "R_2k2_0402"
			(at 330.2 125.73 0)
			(effects
				(font
					(size 1.27 1.27)
					(thickness 0.15)
				)
				(justify left bottom)
				(hide yes)
			)
		)
		(property "Footprint" "antmicro-footprints:R_0402_1005Metric"
			(at 332.74 125.73 0)
			(effects
				(font
					(size 1.27 1.27)
					(thickness 0.15)
				)
				(justify left bottom)
				(hide yes)
			)
		)
		(property "Datasheet" "https://www.bourns.com/docs/product-datasheets/cr.pdf"
			(at 335.28 125.73 0)
			(effects
				(font
					(size 1.27 1.27)
					(thickness 0.15)
				)
				(justify left bottom)
				(hide yes)
			)
		)
		(property "Description" "SMD Chip Resistor, 2.2 kohm, ± 1%, 62.5 mW, 0402 [1005 Metric], Thick Film, General Purpose"
			(at 317.5 146.05 0)
			(effects
				(font
					(size 1.27 1.27)
				)
				(hide yes)
			)
		)
		(property "MPN" "CR0402-FX-2201GLF"
			(at 337.82 125.73 0)
			(effects
				(font
					(size 1.27 1.27)
					(thickness 0.15)
				)
				(justify left bottom)
				(hide yes)
			)
		)
		(property "Manufacturer" "Bourns"
			(at 340.36 125.73 0)
			(effects
				(font
					(size 1.27 1.27)
					(thickness 0.15)
				)
				(justify left bottom)
				(hide yes)
			)
		)
		(property "License" "Apache-2.0"
			(at 342.9 125.73 0)
			(effects
				(font
					(size 1.27 1.27)
					(thickness 0.15)
				)
				(justify left bottom)
				(hide yes)
			)
		)
		(property "Author" "Antmicro"
			(at 345.44 125.73 0)
			(effects
				(font
					(size 1.27 1.27)
					(thickness 0.15)
				)
				(justify left bottom)
				(hide yes)
			)
		)
		(property "Val" "2k2"
			(at 314.96 144.78 90)
			(effects
				(font
					(size 1.27 1.27)
					(thickness 0.15)
				)
				(justify left)
			)
		)
		(property "Tolerance" "1%"
			(at 327.66 125.73 0)
			(effects
				(font
					(size 1.27 1.27)
				)
				(justify left bottom)
				(hide yes)
			)
		)
		(property "Public" ""
			(at 347.98 125.73 0)
			(effects
				(font
					(size 1.27 1.27)
				)
				(justify left bottom)
				(hide yes)
			)
		)
		(pin "1"
		)
		(pin "2"
		)
		(instances
			(project "polarfire-som"
				(path ""
					(reference "R73")
					(unit 1)
				)
			)
		)
	)
	(symbol
		(lib_id "antmicroCapacitors0402:C_100n_0402")
		(at 118.11 102.87 270)
		(unit 1)
		(exclude_from_sim no)
		(in_bom yes)
		(on_board yes)
		(dnp no)
		(property "Reference" "C182"
			(at 116.84 109.22 0)
			(effects
				(font
					(size 1.27 1.27)
					(thickness 0.15)
				)
			)
		)
		(property "Value" "C_100n_0402"
			(at 107.95 123.19 0)
			(effects
				(font
					(size 1.27 1.27)
					(thickness 0.15)
				)
				(justify left bottom)
				(hide yes)
			)
		)
		(property "Footprint" "antmicro-footprints:C_0402_1005Metric"
			(at 105.41 123.19 0)
			(effects
				(font
					(size 1.27 1.27)
					(thickness 0.15)
				)
				(justify left bottom)
				(hide yes)
			)
		)
		(property "Datasheet" "https://www.murata.com/products/productdetail?partno=GRM155R61H104KE14%23"
			(at 102.87 123.19 0)
			(effects
				(font
					(size 1.27 1.27)
					(thickness 0.15)
				)
				(justify left bottom)
				(hide yes)
			)
		)
		(property "Description" "SMD Multilayer Ceramic Capacitor, 0.1 µF, 50 V, 0402 [1005 Metric], ± 10%, X5R, GRM Series"
			(at 118.11 102.87 0)
			(effects
				(font
					(size 1.27 1.27)
				)
				(hide yes)
			)
		)
		(property "MPN" "GRM155R61H104KE14D"
			(at 100.33 123.19 0)
			(effects
				(font
					(size 1.27 1.27)
					(thickness 0.15)
				)
				(justify left bottom)
				(hide yes)
			)
		)
		(property "Manufacturer" "Murata"
			(at 97.79 123.19 0)
			(effects
				(font
					(size 1.27 1.27)
					(thickness 0.15)
				)
				(justify left bottom)
				(hide yes)
			)
		)
		(property "License" "Apache-2.0"
			(at 95.25 123.19 0)
			(effects
				(font
					(size 1.27 1.27)
					(thickness 0.15)
				)
				(justify left bottom)
				(hide yes)
			)
		)
		(property "Author" "Antmicro"
			(at 92.71 123.19 0)
			(effects
				(font
					(size 1.27 1.27)
					(thickness 0.15)
				)
				(justify left bottom)
				(hide yes)
			)
		)
		(property "Val" "100n"
			(at 115.57 99.06 0)
			(effects
				(font
					(size 1.27 1.27)
					(thickness 0.15)
				)
				(justify left bottom)
			)
		)
		(property "Voltage" "50V"
			(at 90.17 123.19 0)
			(effects
				(font
					(size 1.27 1.27)
				)
				(justify left bottom)
				(hide yes)
			)
		)
		(property "Dielectric" "X5R"
			(at 87.63 123.19 0)
			(effects
				(font
					(size 1.27 1.27)
				)
				(justify left bottom)
				(hide yes)
			)
		)
		(property "Public" ""
			(at 85.09 123.19 0)
			(effects
				(font
					(size 1.27 1.27)
				)
				(justify left bottom)
				(hide yes)
			)
		)
		(pin "2"
		)
		(pin "1"
		)
		(instances
			(project "polarfire-som"
				(path ""
					(reference "C182")
					(unit 1)
				)
			)
		)
	)
	(symbol
		(lib_id "antmicroTestPoints:TP_0.75mm_SMD")
		(at 245.11 127 180)
		(unit 1)
		(exclude_from_sim no)
		(in_bom no)
		(on_board yes)
		(dnp no)
		(property "Reference" "TP18"
			(at 237.49 127 0)
			(effects
				(font
					(size 1.27 1.27)
					(thickness 0.15)
				)
			)
		)
		(property "Value" "TP_0.75mm_SMD"
			(at 234.315 123.19 0)
			(effects
				(font
					(size 1.27 1.27)
					(thickness 0.15)
				)
				(justify left bottom)
				(hide yes)
			)
		)
		(property "Footprint" "antmicro-footprints:TP_SMD_0.75mm"
			(at 234.315 120.65 0)
			(effects
				(font
					(size 1.27 1.27)
					(thickness 0.15)
				)
				(justify left bottom)
				(hide yes)
			)
		)
		(property "Datasheet" ""
			(at 227.33 114.3 0)
			(effects
				(font
					(size 1.27 1.27)
					(thickness 0.15)
				)
				(justify left bottom)
				(hide yes)
			)
		)
		(property "Description" "SMT test point"
			(at 245.11 127 0)
			(effects
				(font
					(size 1.27 1.27)
				)
				(hide yes)
			)
		)
		(property "MPN" ""
			(at 234.315 115.57 0)
			(effects
				(font
					(size 1.27 1.27)
					(thickness 0.15)
				)
				(justify left bottom)
				(hide yes)
			)
		)
		(property "Manufacturer" ""
			(at 234.315 120.65 0)
			(effects
				(font
					(size 1.27 1.27)
					(thickness 0.15)
				)
				(justify left bottom)
				(hide yes)
			)
		)
		(property "Author" "Antmicro"
			(at 234.315 118.11 0)
			(effects
				(font
					(size 1.27 1.27)
					(thickness 0.15)
				)
				(justify left bottom)
				(hide yes)
			)
		)
		(property "License" "Apache-2.0"
			(at 234.315 115.57 0)
			(effects
				(font
					(size 1.27 1.27)
					(thickness 0.15)
				)
				(justify left bottom)
				(hide yes)
			)
		)
		(property "Public" "False"
			(at 234.95 113.03 0)
			(effects
				(font
					(size 1.27 1.27)
				)
				(justify left bottom)
				(hide yes)
			)
		)
		(pin "1"
		)
		(instances
			(project "polarfire-som"
				(path ""
					(reference "TP18")
					(unit 1)
				)
			)
		)
	)
)
